FILE_TYPE = CONNECTIVITY;
{Allegro Design Entry HDL 17.2-2016 S081 (4005846) 1/11/2022}
"PAGE_NUMBER" = 48;
0"NC";
1"P3V3_AUX\g";
2"P3V3_AUX\g";
3"P3V3_AUX\g";
4"P3V3_AUX\g";
5"GND\g";
6"GND\g";
7"GND\g";
8"JTAG_SCM_PLD_JTAGEN";
9"FM_BMC_DEBUG_SW_N";
10"MB_JTAG_PLD_R_JTAGEN";
11"FM_JTAG_TCK_MUX_BMC_SEL_R";
12"FM_JTAG_TCK_MUX_BMC_SEL";
13"FM_BMC_DISABLE";
14"GND\g";
%"UNIVERSAL_GND"
"1","(-2225,3025)","0","logical_power","I24";
;
HDL_POWER"GND"
CDS_LIB"logical_power";
"A"7;
%"VCCAUX15"
"1","(-2225,4125)","0","logical_power","I25";
;
HDL_POWER"P3V3_AUX"
CDS_LIB"logical_power";
"A"2;
%"Q_RES"
"2","(-2225,3850)","0","pure_quanta","I33";
;
TOLERANCE"1%"
VALUE"4.7K"
WATTAGE"1/16W"
PACK_TYPE"0402LF"
MATERIAL"EMPTY"
PART_NUMBER"CS24702FB10"
CDS_LIB"pure_quanta"
$LOCATION"R615"
CDS_LOCATION"R615"
$SEC"1"
CDS_SEC"1";
"A"
$PN"1"2;
"B"
$PN"2"13;
%"UNIVERSAL_GND"
"1","(-375,1425)","2","logical_power","I38";
;
CDS_LIB"logical_power"
HDL_POWER"GND";
"A"6;
%"Q_RES"
"2","(-375,1750)","0","pure_quanta","I39";
;
PACK_TYPE"0402LF"
PART_NUMBER"CS41002FB09"
WATTAGE"1/16W"
TOLERANCE"1%"
VALUE"100K"
MATERIAL"CHIP"
CDS_LIB"pure_quanta"
LOCATION"R620"
$SEC"1"
CDS_SEC"1";
"A"
$PN"1"12;
"B"
$PN"2"6;
%"Q_RES"
"1","(-1150,2000)","6","pure_quanta","I40";
;
VALUE"0"
MATERIAL"CHIP"
TOLERANCE"5%"
CDS_LIB"pure_quanta"
WATTAGE"1/16W"
PACK_TYPE"0402LF"
PART_NUMBER"CS00002JB13"
LOCATION"R616"
$SEC"1"
CDS_SEC"1";
"B"
$PN"2"12;
"A"
$PN"1"11;
%"VCCAUX15"
"1","(-2250,2575)","0","logical_power","I41";
;
HDL_POWER"P3V3_AUX"
CDS_LIB"logical_power";
"A"3;
%"Q_RES"
"2","(-2250,2300)","0","pure_quanta","I42";
;
WATTAGE"1/16W"
MATERIAL"EMPTY"
PACK_TYPE"0402LF"
TOLERANCE"1%"
VALUE"4.7K"
PART_NUMBER"CS24702FB10"
CDS_LIB"pure_quanta"
$LOCATION"R881"
CDS_LOCATION"R881"
$SEC"1"
CDS_SEC"1";
"A"
$PN"1"3;
"B"
$PN"2"11;
%"VCCAUX15"
"1","(-575,1025)","0","logical_power","I47";
;
HDL_POWER"P3V3_AUX"
CDS_LIB"logical_power";
"A"1;
%"Q_RES"
"2","(-575,800)","0","pure_quanta","I48";
;
VALUE"4.7K"
PACK_TYPE"0402LF"
WATTAGE"1/16W"
MATERIAL"CHIP"
TOLERANCE"1%"
CDS_LIB"pure_quanta"
PART_NUMBER"CS24702FB06"
LOCATION"R624"
$SEC"1"
CDS_SEC"1";
"A"
$PN"1"1;
"B"
$PN"2"9;
%"VCCAUX15"
"1","(-1075,900)","0","logical_power","I49";
;
HDL_POWER"P3V3_AUX"
CDS_LIB"logical_power";
"A"4;
%"Q_RES"
"1","(-950,250)","0","pure_quanta","I50";
;
MATERIAL"CHIP"
VALUE"33.2"
CDS_LIB"pure_quanta"
WATTAGE"1/16W"
PACK_TYPE"0402LF"
PART_NUMBER"CS03322FB03"
TOLERANCE"1%"
LOCATION"R509"
$SEC"1"
CDS_SEC"1";
"B"
$PN"2"8;
"A"
$PN"1"10;
%"Q_RES"
"2","(-1075,675)","0","pure_quanta","I51";
;
VALUE"10K"
TOLERANCE"1%"
WATTAGE"1/16W"
MATERIAL"CHIP"
PACK_TYPE"0402LF"
PART_NUMBER"CS31002FB08"
CDS_LIB"pure_quanta"
LOCATION"R508"
$SEC"1"
CDS_SEC"1";
"A"
$PN"1"4;
"B"
$PN"2"10;
%"Q_RES"
"2","(-2050,-75)","0","pure_quanta","I52";
;
TOLERANCE"1%"
VALUE"100"
MATERIAL"EMPTY"
PACK_TYPE"0402LF"
PART_NUMBER"CS11002FB07"
CDS_LIB"pure_quanta"
WATTAGE"1/16W"
LOCATION"R507"
$SEC"1"
CDS_SEC"1";
"A"
$PN"1"10;
"B"
$PN"2"14;
%"Q_RES"
"2","(-2675,-50)","0","pure_quanta","I53";
;
PACK_TYPE"0402LF"
TOLERANCE"1%"
VALUE"100"
PART_NUMBER"CS11002FB07"
MATERIAL"EMPTY"
WATTAGE"1/16W"
CDS_LIB"pure_quanta"
LOCATION"R506"
$SEC"1"
CDS_SEC"1";
"A"
$PN"1"9;
"B"
$PN"2"5;
%"UNIVERSAL_GND"
"1","(-2050,-225)","2","logical_power","I54";
;
HDL_POWER"GND"
CDS_LIB"logical_power";
"A"14;
%"UNIVERSAL_GND"
"1","(-2675,-225)","2","logical_power","I55";
;
HDL_POWER"GND"
CDS_LIB"logical_power";
"A"5;
%"Q_RES"
"2","(-2225,3300)","0","pure_quanta","I56";
;
VALUE"100"
TOLERANCE"1%"
WATTAGE"1/16W"
PART_NUMBER"CS11002FB07"
PACK_TYPE"0402LF"
MATERIAL"EMPTY"
CDS_LIB"pure_quanta"
LOCATION"R431"
$SEC"1"
CDS_SEC"1";
"A"
$PN"1"13;
"B"
$PN"2"7;
END.
